(kicad_pcb
	(version 20260206)
	(generator "pcbnew")
	(generator_version "10.0")
	(general
		(thickness 1.6)
		(legacy_teardrops no)
	)
	(paper "A4")
	(title_block
		(title "timecard-production-celestica-r4006 — R4006-B0001-02_R01.brd")
		(comment 1 "Time Appliance Project (Time Card) / footprints 406-412 of 1113")
	)
	(layers
		(0 "F.Cu" signal "TOP")
		(4 "In1.Cu" signal "L02_GND1")
		(6 "In2.Cu" signal "L03_SIG1")
		(8 "In3.Cu" signal "L04_GND2")
		(10 "In4.Cu" signal "L05_VCC1")
		(12 "In5.Cu" signal "L06_VCC2")
		(14 "In6.Cu" signal "L07_GND3")
		(16 "In7.Cu" signal "L08_SIG2")
		(18 "In8.Cu" signal "L09_GND4")
		(2 "B.Cu" signal "BOTTOM")
		(9 "F.Adhes" user "F.Adhesive")
		(11 "B.Adhes" user "B.Adhesive")
		(13 "F.Paste" user "Package Geometry/Pastemask Top")
		(15 "B.Paste" user "Package Geometry/Pastemask Bottom")
		(5 "F.SilkS" user "Ref Des/Silkscreen Top")
		(7 "B.SilkS" user "Ref Des/Silkscreen Bottom")
		(1 "F.Mask" user "Board Geometry/Soldermask Top")
		(3 "B.Mask" user "Board Geometry/Soldermask Bottom")
		(17 "Dwgs.User" user "User.Drawings")
		(19 "Cmts.User" user "User.Comments")
		(21 "Eco1.User" user "User.Eco1")
		(23 "Eco2.User" user "User.Eco2")
		(25 "Edge.Cuts" user "Board Geometry/Outline")
		(27 "Margin" user)
		(31 "F.CrtYd" user "Package Geometry/Place Bound Top")
		(29 "B.CrtYd" user "Package Geometry/Place Bound Bottom")
		(35 "F.Fab" user "Ref Des/Assembly Top")
		(33 "B.Fab" user "Ref Des/Assembly Bottom")
	)
	(footprint ""
		(layer "F.Cu")
		(at 16.852392 -66.3956 180)
		(property "Reference" "R347"
			(at -0.927608 -1.53035 0)
			(unlocked yes)
			(layer "F.SilkS")
			(effects
				(font
					(size 0.635 0.4064)
					(thickness 0.1524)
				)
			)
		)
		(property "Value" "VAL*"
			(at 0.02032 2.13233 180)
			(unlocked yes)
			(layer "F.Fab")
			(hide yes)
			(effects
				(font
					(size 0.7874 0.5842)
					(thickness 0.1524)
				)
			)
		)
		(property "Tolerance" "TOL*"
			(at 0.044704 3.05435 180)
			(unlocked yes)
			(layer "Cmts.User")
			(hide yes)
			(effects
				(font
					(size 0.7874 0.5842)
					(thickness 0.1524)
				)
			)
		)
		(property "User Part Number" "PARTNUM*"
			(at 0.02032 4.024884 180)
			(unlocked yes)
			(layer "Cmts.User")
			(hide yes)
			(effects
				(font
					(size 0.7874 0.5842)
					(thickness 0.1524)
				)
			)
		)
		(property "Device Type" "RESISTOR-G155-100R0-J0,0OHM,-"
			(at 0.008382 1.210564 180)
			(unlocked yes)
			(layer "F.Fab")
			(hide yes)
			(effects
				(font
					(size 0.7874 0.5842)
					(thickness 0.1524)
				)
			)
		)
		(duplicate_pad_numbers_are_jumpers no)
		(fp_line
			(start 1.143 0.5588)
			(end 1.143 -0.5588)
			(stroke
				(width 0.1)
				(type default)
			)
			(layer "F.SilkS")
		)
		(fp_line
			(start 1.143 -0.5588)
			(end -1.143 -0.5588)
			(stroke
				(width 0.1)
				(type default)
			)
			(layer "F.SilkS")
		)
		(fp_line
			(start -1.143 0.5588)
			(end 1.143 0.5588)
			(stroke
				(width 0.1)
				(type default)
			)
			(layer "F.SilkS")
		)
		(fp_line
			(start -1.143 -0.5588)
			(end -1.143 0.5588)
			(stroke
				(width 0.1)
				(type default)
			)
			(layer "F.SilkS")
		)
		(fp_poly
			(pts
				(xy -1.143 0.5588) (xy 1.143 0.5588) (xy 1.143 -0.5588) (xy -1.143 -0.5588)
			)
			(stroke
				(width 0)
				(type default)
			)
			(fill no)
			(layer "F.CrtYd")
		)
		(fp_line
			(start 0.508 0.3048)
			(end 0.508 -0.3048)
			(stroke
				(width 0.1)
				(type default)
			)
			(layer "F.Fab")
		)
		(fp_line
			(start 0.508 -0.3048)
			(end -0.508 -0.3048)
			(stroke
				(width 0.1)
				(type default)
			)
			(layer "F.Fab")
		)
		(fp_line
			(start -0.508 0.3048)
			(end 0.508 0.3048)
			(stroke
				(width 0.1)
				(type default)
			)
			(layer "F.Fab")
		)
		(fp_line
			(start -0.508 -0.3048)
			(end -0.508 0.3048)
			(stroke
				(width 0.1)
				(type default)
			)
			(layer "F.Fab")
		)
		(pad "1" smd rect
			(at -0.5334 0 180)
			(size 0.7112 0.6096)
			(layers "F.Cu" "F.Mask" "F.Paste")
			(net "UNNAMED_8_ICP10100LGA10_I24_R_2")
		)
		(pad "2" smd rect
			(at 0.5334 0 180)
			(size 0.7112 0.6096)
			(layers "F.Cu" "F.Mask" "F.Paste")
			(net "XP1R8V_ICP10100")
		)
		(zone
			(layer "F.Cu")
			(hatch none 0.5)
			(connect_pads
				(clearance 0)
			)
			(min_thickness 0.25)
			(keepout
				(tracks allowed)
				(vias not_allowed)
				(pads allowed)
				(copperpour not_allowed)
				(footprints allowed)
			)
			(placement
				(enabled no)
				(sheetname "")
			)
			(fill
				(thermal_gap 0.5)
				(thermal_bridge_width 0.5)
				(island_removal_mode 0)
			)
			(polygon
				(pts
					(xy 16.928592 -66.7004) (xy 16.776192 -66.7004) (xy 16.776192 -66.0908) (xy 16.928592 -66.0908)
				)
			)
		)
		(zone
			(layer "F.Cu")
			(hatch none 0.5)
			(connect_pads
				(clearance 0)
			)
			(min_thickness 0.25)
			(keepout
				(tracks not_allowed)
				(vias allowed)
				(pads allowed)
				(copperpour not_allowed)
				(footprints allowed)
			)
			(placement
				(enabled no)
				(sheetname "")
			)
			(fill
				(thermal_gap 0.5)
				(thermal_bridge_width 0.5)
				(island_removal_mode 0)
			)
			(polygon
				(pts
					(xy 16.928592 -66.7004) (xy 16.776192 -66.7004) (xy 16.776192 -66.0908) (xy 16.928592 -66.0908)
				)
			)
		)
	)
	(footprint ""
		(layer "F.Cu")
		(at 77.47 -98.171 -90)
		(property "Reference" "L2"
			(at 0.127 5.04063 90)
			(unlocked yes)
			(layer "F.SilkS")
			(effects
				(font
					(size 0.7874 0.5842)
					(thickness 0.1524)
				)
			)
		)
		(property "Value" "VAL*"
			(at -0.035306 8.510778 270)
			(unlocked yes)
			(layer "F.Fab")
			(hide yes)
			(effects
				(font
					(size 0.7874 0.5842)
					(thickness 0.1524)
				)
			)
		)
		(property "Tolerance" "TOL*"
			(at -0.061722 7.222744 270)
			(unlocked yes)
			(layer "Cmts.User")
			(hide yes)
			(effects
				(font
					(size 0.7874 0.5842)
					(thickness 0.1524)
				)
			)
		)
		(property "User Part Number" "PARTNUM*"
			(at 0 6.106668 270)
			(unlocked yes)
			(layer "Cmts.User")
			(hide yes)
			(effects
				(font
					(size 0.7874 0.5842)
					(thickness 0.1524)
				)
			)
		)
		(property "Device Type" "INDUCTOR_2-G190-10424-01,4.7UHA"
			(at 0 4.912868 270)
			(unlocked yes)
			(layer "F.Fab")
			(hide yes)
			(effects
				(font
					(size 0.7874 0.5842)
					(thickness 0.1524)
				)
			)
		)
		(duplicate_pad_numbers_are_jumpers no)
		(fp_line
			(start -4.448302 3.803904)
			(end -4.448302 -3.803904)
			(stroke
				(width 0.1)
				(type default)
			)
			(layer "F.SilkS")
		)
		(fp_line
			(start 4.448302 3.803904)
			(end -4.448302 3.803904)
			(stroke
				(width 0.1)
				(type default)
			)
			(layer "F.SilkS")
		)
		(fp_line
			(start -4.448302 -3.803904)
			(end 4.448302 -3.803904)
			(stroke
				(width 0.1)
				(type default)
			)
			(layer "F.SilkS")
		)
		(fp_line
			(start 4.448302 -3.803904)
			(end 4.448302 3.803904)
			(stroke
				(width 0.1)
				(type default)
			)
			(layer "F.SilkS")
		)
		(fp_rect
			(start 4.702302 -4.057904)
			(end -4.702302 4.057904)
			(stroke
				(width 0)
				(type default)
			)
			(fill no)
			(layer "F.CrtYd")
		)
		(fp_line
			(start -3.800094 3.549904)
			(end -3.800094 -3.549904)
			(stroke
				(width 0.1)
				(type default)
			)
			(layer "F.Fab")
		)
		(fp_line
			(start 3.800094 3.549904)
			(end -3.800094 3.549904)
			(stroke
				(width 0.1)
				(type default)
			)
			(layer "F.Fab")
		)
		(fp_line
			(start -3.800094 -3.549904)
			(end 3.800094 -3.549904)
			(stroke
				(width 0.1)
				(type default)
			)
			(layer "F.Fab")
		)
		(fp_line
			(start 3.800094 -3.549904)
			(end 3.800094 3.549904)
			(stroke
				(width 0.1)
				(type default)
			)
			(layer "F.Fab")
		)
		(fp_text user "1"
			(at -5.42163 0 0)
			(unlocked yes)
			(layer "F.SilkS")
			(effects
				(font
					(size 0.7874 0.5842)
					(thickness 0.1524)
				)
			)
		)
		(fp_text user "2"
			(at 5.50037 -0.254 0)
			(unlocked yes)
			(layer "F.SilkS")
			(effects
				(font
					(size 0.7874 0.5842)
					(thickness 0.1524)
				)
			)
		)
		(fp_text user "1"
			(at -4.67233 0 0)
			(unlocked yes)
			(layer "F.Fab")
			(effects
				(font
					(size 0.7874 0.5842)
					(thickness 0.1524)
				)
			)
		)
		(fp_text user "2"
			(at 4.59867 0 0)
			(unlocked yes)
			(layer "F.Fab")
			(effects
				(font
					(size 0.7874 0.5842)
					(thickness 0.1524)
				)
			)
		)
		(pad "1" smd rect
			(at -2.975102 0 270)
			(size 2.4384 3.7084)
			(layers "F.Cu" "F.Mask" "F.Paste")
			(net "XP3R3V_SW")
		)
		(pad "2" smd rect
			(at 2.975102 0 270)
			(size 2.4384 3.7084)
			(layers "F.Cu" "F.Mask" "F.Paste")
			(net "XP3R3V")
		)
		(zone
			(layer "F.Cu")
			(hatch none 0.5)
			(connect_pads
				(clearance 0)
			)
			(min_thickness 0.25)
			(keepout
				(tracks allowed)
				(vias not_allowed)
				(pads allowed)
				(copperpour not_allowed)
				(footprints allowed)
			)
			(placement
				(enabled no)
				(sheetname "")
			)
			(fill
				(thermal_gap 0.5)
				(thermal_bridge_width 0.5)
				(island_removal_mode 0)
			)
			(polygon
				(pts
					(xy 73.920096 -101.971094) (xy 75.6158 -101.971094) (xy 75.6158 -99.926902) (xy 79.3242 -99.926902)
					(xy 79.3242 -101.971094) (xy 81.019904 -101.971094) (xy 81.019904 -94.370906) (xy 79.3242 -94.370906)
					(xy 79.3242 -96.415098) (xy 75.6158 -96.415098) (xy 75.6158 -94.370906) (xy 73.920096 -94.370906)
				)
			)
		)
	)
	(footprint ""
		(layer "F.Cu")
		(at 48.768 -122.555)
		(property "Reference" "SP77"
			(at 0 0 0)
			(layer "F.SilkS")
			(hide yes)
			(effects
				(font
					(size 1.27 1.27)
				)
			)
		)
		(property "Value" ""
			(at 0 0 0)
			(layer "F.Fab")
			(effects
				(font
					(size 1.27 1.27)
				)
			)
		)
		(duplicate_pad_numbers_are_jumpers no)
	)
	(footprint ""
		(layer "F.Cu")
		(at 84.0232 -105.0798 180)
		(property "Reference" "C53"
			(at 2.794 -0.16637 0)
			(unlocked yes)
			(layer "F.SilkS")
			(effects
				(font
					(size 0.7874 0.5842)
					(thickness 0.1524)
				)
			)
		)
		(property "Value" "VAL*"
			(at 0.0762 2.067306 180)
			(unlocked yes)
			(layer "F.Fab")
			(hide yes)
			(effects
				(font
					(size 0.7874 0.5842)
					(thickness 0.1524)
				)
			)
		)
		(property "Tolerance" "TOL*"
			(at 0.0762 3.032506 180)
			(unlocked yes)
			(layer "Cmts.User")
			(hide yes)
			(effects
				(font
					(size 0.7874 0.5842)
					(thickness 0.1524)
				)
			)
		)
		(property "User Part Number" "PARTNUM*"
			(at 0.1016 4.023106 180)
			(unlocked yes)
			(layer "Cmts.User")
			(hide yes)
			(effects
				(font
					(size 0.7874 0.5842)
					(thickness 0.1524)
				)
			)
		)
		(property "Device Type" "CAPACITOR-G105-0B104-EK,0.1UF,A"
			(at 0.0508 1.127506 180)
			(unlocked yes)
			(layer "F.Fab")
			(hide yes)
			(effects
				(font
					(size 0.7874 0.5842)
					(thickness 0.1524)
				)
			)
		)
		(duplicate_pad_numbers_are_jumpers no)
		(fp_line
			(start 1.143 0.5588)
			(end 1.143 -0.5588)
			(stroke
				(width 0.1)
				(type default)
			)
			(layer "F.SilkS")
		)
		(fp_line
			(start 1.143 -0.5588)
			(end -1.143 -0.5588)
			(stroke
				(width 0.1)
				(type default)
			)
			(layer "F.SilkS")
		)
		(fp_line
			(start -1.143 0.5588)
			(end 1.143 0.5588)
			(stroke
				(width 0.1)
				(type default)
			)
			(layer "F.SilkS")
		)
		(fp_line
			(start -1.143 -0.5588)
			(end -1.143 0.5588)
			(stroke
				(width 0.1)
				(type default)
			)
			(layer "F.SilkS")
		)
		(fp_rect
			(start 1.143 -0.5588)
			(end -1.143 0.5588)
			(stroke
				(width 0)
				(type default)
			)
			(fill no)
			(layer "F.CrtYd")
		)
		(fp_line
			(start 0.508 0.3048)
			(end 0.508 -0.3048)
			(stroke
				(width 0.1)
				(type default)
			)
			(layer "F.Fab")
		)
		(fp_line
			(start 0.508 -0.3048)
			(end -0.508 -0.3048)
			(stroke
				(width 0.1)
				(type default)
			)
			(layer "F.Fab")
		)
		(fp_line
			(start -0.508 0.3048)
			(end 0.508 0.3048)
			(stroke
				(width 0.1)
				(type default)
			)
			(layer "F.Fab")
		)
		(fp_line
			(start -0.508 -0.3048)
			(end -0.508 0.3048)
			(stroke
				(width 0.1)
				(type default)
			)
			(layer "F.Fab")
		)
		(pad "1" smd rect
			(at -0.5334 0 180)
			(size 0.7112 0.6096)
			(layers "F.Cu" "F.Mask" "F.Paste")
			(net "VIN_XP3R3")
		)
		(pad "2" smd rect
			(at 0.5334 0 180)
			(size 0.7112 0.6096)
			(layers "F.Cu" "F.Mask" "F.Paste")
			(net "SG")
		)
		(zone
			(layer "F.Cu")
			(hatch none 0.5)
			(connect_pads
				(clearance 0)
			)
			(min_thickness 0.25)
			(keepout
				(tracks allowed)
				(vias not_allowed)
				(pads allowed)
				(copperpour not_allowed)
				(footprints allowed)
			)
			(placement
				(enabled no)
				(sheetname "")
			)
			(fill
				(thermal_gap 0.5)
				(thermal_bridge_width 0.5)
				(island_removal_mode 0)
			)
			(polygon
				(pts
					(xy 83.947 -104.775) (xy 84.0994 -104.775) (xy 84.0994 -105.3846) (xy 83.947 -105.3846)
				)
			)
		)
	)
	(footprint ""
		(layer "F.Cu")
		(at 79.883 -41.783 180)
		(property "Reference" "R287"
			(at -0.381 -13.88237 0)
			(unlocked yes)
			(layer "F.SilkS")
			(effects
				(font
					(size 0.7874 0.5842)
					(thickness 0.1524)
				)
			)
		)
		(property "Value" "VAL*"
			(at 0.02032 2.13233 180)
			(unlocked yes)
			(layer "F.Fab")
			(hide yes)
			(effects
				(font
					(size 0.7874 0.5842)
					(thickness 0.1524)
				)
			)
		)
		(property "Device Type" "RESISTOR-G155-14701-01,4.7KOHMA"
			(at 0.008382 1.210564 180)
			(unlocked yes)
			(layer "F.Fab")
			(hide yes)
			(effects
				(font
					(size 0.7874 0.5842)
					(thickness 0.1524)
				)
			)
		)
		(property "User Part Number" "PARTNUM*"
			(at 0.02032 4.024884 180)
			(unlocked yes)
			(layer "Cmts.User")
			(hide yes)
			(effects
				(font
					(size 0.7874 0.5842)
					(thickness 0.1524)
				)
			)
		)
		(property "Tolerance" "TOL*"
			(at 0.044704 3.05435 180)
			(unlocked yes)
			(layer "Cmts.User")
			(hide yes)
			(effects
				(font
					(size 0.7874 0.5842)
					(thickness 0.1524)
				)
			)
		)
		(duplicate_pad_numbers_are_jumpers no)
		(fp_line
			(start 1.143 0.5588)
			(end 1.143 -0.5588)
			(stroke
				(width 0.1)
				(type default)
			)
			(layer "F.SilkS")
		)
		(fp_line
			(start 1.143 -0.5588)
			(end -1.143 -0.5588)
			(stroke
				(width 0.1)
				(type default)
			)
			(layer "F.SilkS")
		)
		(fp_line
			(start -1.143 0.5588)
			(end 1.143 0.5588)
			(stroke
				(width 0.1)
				(type default)
			)
			(layer "F.SilkS")
		)
		(fp_line
			(start -1.143 -0.5588)
			(end -1.143 0.5588)
			(stroke
				(width 0.1)
				(type default)
			)
			(layer "F.SilkS")
		)
		(fp_rect
			(start 1.143 -0.5588)
			(end -1.143 0.5588)
			(stroke
				(width 0)
				(type default)
			)
			(fill no)
			(layer "F.CrtYd")
		)
		(fp_line
			(start 0.508 0.3048)
			(end 0.508 -0.3048)
			(stroke
				(width 0.1)
				(type default)
			)
			(layer "F.Fab")
		)
		(fp_line
			(start 0.508 -0.3048)
			(end -0.508 -0.3048)
			(stroke
				(width 0.1)
				(type default)
			)
			(layer "F.Fab")
		)
		(fp_line
			(start -0.508 0.3048)
			(end 0.508 0.3048)
			(stroke
				(width 0.1)
				(type default)
			)
			(layer "F.Fab")
		)
		(fp_line
			(start -0.508 -0.3048)
			(end -0.508 0.3048)
			(stroke
				(width 0.1)
				(type default)
			)
			(layer "F.Fab")
		)
		(pad "1" smd rect
			(at -0.5334 0 180)
			(size 0.7112 0.6096)
			(layers "F.Cu" "F.Mask" "F.Paste")
			(net "FPGA_IN_MAC_ALARM_OUT_N")
		)
		(pad "2" smd rect
			(at 0.5334 0 180)
			(size 0.7112 0.6096)
			(layers "F.Cu" "F.Mask" "F.Paste")
			(net "XP3R3V_FPGA")
		)
		(zone
			(layer "F.Cu")
			(hatch none 0.5)
			(connect_pads
				(clearance 0)
			)
			(min_thickness 0.25)
			(keepout
				(tracks allowed)
				(vias not_allowed)
				(pads allowed)
				(copperpour not_allowed)
				(footprints allowed)
			)
			(placement
				(enabled no)
				(sheetname "")
			)
			(fill
				(thermal_gap 0.5)
				(thermal_bridge_width 0.5)
				(island_removal_mode 0)
			)
			(polygon
				(pts
					(xy 79.8068 -41.4782) (xy 79.9592 -41.4782) (xy 79.9592 -42.0878) (xy 79.8068 -42.0878)
				)
			)
		)
	)
	(footprint ""
		(layer "F.Cu")
		(at 70.485 -132.207)
		(property "Reference" "SP40"
			(at 0 0 0)
			(layer "F.SilkS")
			(hide yes)
			(effects
				(font
					(size 1.27 1.27)
				)
			)
		)
		(property "Value" ""
			(at 0 0 0)
			(layer "F.Fab")
			(effects
				(font
					(size 1.27 1.27)
				)
			)
		)
		(duplicate_pad_numbers_are_jumpers no)
	)
	(footprint ""
		(layer "F.Cu")
		(at 97.4598 -68.072)
		(property "Reference" "R186"
			(at -28.067 -19.014694 0)
			(unlocked yes)
			(layer "F.SilkS")
			(effects
				(font
					(size 0.7874 0.5842)
					(thickness 0.1524)
				)
			)
		)
		(property "Value" "VAL*"
			(at 0.02032 2.13233 0)
			(unlocked yes)
			(layer "F.Fab")
			(hide yes)
			(effects
				(font
					(size 0.7874 0.5842)
					(thickness 0.1524)
				)
			)
		)
		(property "Tolerance" "TOL*"
			(at 0.044704 3.05435 0)
			(unlocked yes)
			(layer "Cmts.User")
			(hide yes)
			(effects
				(font
					(size 0.7874 0.5842)
					(thickness 0.1524)
				)
			)
		)
		(property "User Part Number" "PARTNUM*"
			(at 0.02032 4.024884 0)
			(unlocked yes)
			(layer "Cmts.User")
			(hide yes)
			(effects
				(font
					(size 0.7874 0.5842)
					(thickness 0.1524)
				)
			)
		)
		(property "Device Type" "RESISTOR-G155-03001-01,3KOHM,1%"
			(at 0.008382 1.210564 0)
			(unlocked yes)
			(layer "F.Fab")
			(hide yes)
			(effects
				(font
					(size 0.7874 0.5842)
					(thickness 0.1524)
				)
			)
		)
		(duplicate_pad_numbers_are_jumpers no)
		(fp_line
			(start -1.143 -0.5588)
			(end -1.143 0.5588)
			(stroke
				(width 0.1)
				(type default)
			)
			(layer "F.SilkS")
		)
		(fp_line
			(start -1.143 0.5588)
			(end 1.143 0.5588)
			(stroke
				(width 0.1)
				(type default)
			)
			(layer "F.SilkS")
		)
		(fp_line
			(start 1.143 -0.5588)
			(end -1.143 -0.5588)
			(stroke
				(width 0.1)
				(type default)
			)
			(layer "F.SilkS")
		)
		(fp_line
			(start 1.143 0.5588)
			(end 1.143 -0.5588)
			(stroke
				(width 0.1)
				(type default)
			)
			(layer "F.SilkS")
		)
		(fp_poly
			(pts
				(xy -1.143 0.5588) (xy 1.143 0.5588) (xy 1.143 -0.5588) (xy -1.143 -0.5588)
			)
			(stroke
				(width 0)
				(type default)
			)
			(fill no)
			(layer "F.CrtYd")
		)
		(fp_line
			(start -0.508 -0.3048)
			(end -0.508 0.3048)
			(stroke
				(width 0.1)
				(type default)
			)
			(layer "F.Fab")
		)
		(fp_line
			(start -0.508 0.3048)
			(end 0.508 0.3048)
			(stroke
				(width 0.1)
				(type default)
			)
			(layer "F.Fab")
		)
		(fp_line
			(start 0.508 -0.3048)
			(end -0.508 -0.3048)
			(stroke
				(width 0.1)
				(type default)
			)
			(layer "F.Fab")
		)
		(fp_line
			(start 0.508 0.3048)
			(end 0.508 -0.3048)
			(stroke
				(width 0.1)
				(type default)
			)
			(layer "F.Fab")
		)
		(pad "1" smd rect
			(at -0.5334 0)
			(size 0.7112 0.6096)
			(layers "F.Cu" "F.Mask" "F.Paste")
			(net "SG")
		)
		(pad "2" smd rect
			(at 0.5334 0)
			(size 0.7112 0.6096)
			(layers "F.Cu" "F.Mask" "F.Paste")
			(net "XP1R2V_FB")
		)
		(zone
			(layer "F.Cu")
			(hatch none 0.5)
			(connect_pads
				(clearance 0)
			)
			(min_thickness 0.25)
			(keepout
				(tracks not_allowed)
				(vias allowed)
				(pads allowed)
				(copperpour not_allowed)
				(footprints allowed)
			)
			(placement
				(enabled no)
				(sheetname "")
			)
			(fill
				(thermal_gap 0.5)
				(thermal_bridge_width 0.5)
				(island_removal_mode 0)
			)
			(polygon
				(pts
					(xy 97.3836 -67.7672) (xy 97.536 -67.7672) (xy 97.536 -68.3768) (xy 97.3836 -68.3768)
				)
			)
		)
		(zone
			(layer "F.Cu")
			(hatch none 0.5)
			(connect_pads
				(clearance 0)
			)
			(min_thickness 0.25)
			(keepout
				(tracks allowed)
				(vias not_allowed)
				(pads allowed)
				(copperpour not_allowed)
				(footprints allowed)
			)
			(placement
				(enabled no)
				(sheetname "")
			)
			(fill
				(thermal_gap 0.5)
				(thermal_bridge_width 0.5)
				(island_removal_mode 0)
			)
			(polygon
				(pts
					(xy 97.3836 -67.7672) (xy 97.536 -67.7672) (xy 97.536 -68.3768) (xy 97.3836 -68.3768)
				)
			)
		)
	)
)
